# S9S_MB_2U (Grand Teton) — schematic netlist excerpt (pin names and nets, part order shuffled) for the footprints in the layout excerpt that follows; sources: Cadence DE-HDL packaged netlist, KiCad conversion of 03242023_DA0F0TMBIJ0_F0T_Motherboard_J_brd_V01_OCP.brd

R166  Q_RES  0 5% CHIP  pkg 0402LF  page 124 : A = PWRGD_DRAMPWRGD_CPU0_GH_R_LVC1 ; B = PWRGD_DRAMPWRGD_CPU0_GH_LVC1_R2
R322  Q_RES  33.2 1% CHIP  pkg 0402LF  page 14 : A = H_CPU0_PMSYNC_CPU1_R ; B = H_CPU0_PMSYNC_CPU1_R1

(kicad_pcb
	(version 20260206)
	(generator "pcbnew")
	(generator_version "10.0")
	(general
		(thickness 1.6)
		(legacy_teardrops no)
	)
	(paper "A4")
	(title_block
		(title "03242023_DA0F0TMBIJ0_F0T_Motherboard_J_brd_V01_OCP.brd")
		(comment 1 "Grand Teton / footprints 4786-4787 of 6105")
	)
	(layers
		(0 "F.Cu" signal "TOP")
		(4 "In1.Cu" signal "GND")
		(6 "In2.Cu" signal "IN1")
		(8 "In3.Cu" signal "GND1")
		(10 "In4.Cu" signal "IN2")
		(12 "In5.Cu" signal "GND2")
		(14 "In6.Cu" signal "IN3")
		(16 "In7.Cu" signal "GND3")
		(18 "In8.Cu" signal "VCC")
		(20 "In9.Cu" signal "VCC1")
		(22 "In10.Cu" signal "GND4")
		(24 "In11.Cu" signal "IN4")
		(26 "In12.Cu" signal "GND5")
		(28 "In13.Cu" signal "IN5")
		(30 "In14.Cu" signal "GND6")
		(32 "In15.Cu" signal "IN6")
		(34 "In16.Cu" signal "GND7")
		(2 "B.Cu" signal "BOTTOM")
		(9 "F.Adhes" user "F.Adhesive")
		(11 "B.Adhes" user "B.Adhesive")
		(13 "F.Paste" user "Package Geometry/Pastemask Top")
		(15 "B.Paste" user "Package Geometry/Pastemask Bottom")
		(5 "F.SilkS" user "Ref Des/Silkscreen Top")
		(7 "B.SilkS" user "Ref Des/Silkscreen Bottom")
		(1 "F.Mask" user "Board Geometry/Soldermask Top")
		(3 "B.Mask" user "Board Geometry/Soldermask Bottom")
		(17 "Dwgs.User" user "User.Drawings")
		(19 "Cmts.User" user "User.Comments")
		(21 "Eco1.User" user "User.Eco1")
		(23 "Eco2.User" user "User.Eco2")
		(25 "Edge.Cuts" user "Board Geometry/Outline")
		(27 "Margin" user)
		(31 "F.CrtYd" user "Package Geometry/Place Bound Top")
		(29 "B.CrtYd" user "Package Geometry/Place Bound Bottom")
		(35 "F.Fab" user "Ref Des/Assembly Top")
		(33 "B.Fab" user "Ref Des/Assembly Bottom")
	)
	(footprint ""
		(layer "B.Cu")
		(at 387.90499 -190.82131 90)
		(property "Reference" "R322"
			(at 0 0 90)
			(layer "B.SilkS")
			(hide yes)
			(effects
				(font
					(size 1.27 1.27)
				)
				(justify mirror)
			)
		)
		(property "Value" ""
			(at 0 0 90)
			(layer "B.Fab")
			(effects
				(font
					(size 1.27 1.27)
				)
				(justify mirror)
			)
		)
		(duplicate_pad_numbers_are_jumpers no)
		(fp_line
			(start 0.7874 -0.4064)
			(end -0.7874 -0.4064)
			(stroke
				(width 0.1524)
				(type default)
			)
			(layer "B.SilkS")
		)
		(fp_line
			(start -0.7874 -0.4064)
			(end -0.7874 0.4064)
			(stroke
				(width 0.1524)
				(type default)
			)
			(layer "B.SilkS")
		)
		(fp_line
			(start 0.7874 0.4064)
			(end 0.7874 -0.4064)
			(stroke
				(width 0.1524)
				(type default)
			)
			(layer "B.SilkS")
		)
		(fp_line
			(start -0.7874 0.4064)
			(end 0.7874 0.4064)
			(stroke
				(width 0.1524)
				(type default)
			)
			(layer "B.SilkS")
		)
		(fp_line
			(start 0.67945 -0.305054)
			(end 0.12065 -0.305054)
			(stroke
				(width 0.1)
				(type default)
			)
			(layer "B.Fab")
		)
		(fp_line
			(start 0.12065 -0.305054)
			(end 0.12065 -0.2794)
			(stroke
				(width 0.1)
				(type default)
			)
			(layer "B.Fab")
		)
		(fp_line
			(start -0.12065 -0.3048)
			(end -0.67945 -0.3048)
			(stroke
				(width 0.1)
				(type default)
			)
			(layer "B.Fab")
		)
		(fp_line
			(start -0.67945 -0.3048)
			(end -0.67945 0.3048)
			(stroke
				(width 0.1)
				(type default)
			)
			(layer "B.Fab")
		)
		(fp_line
			(start 0.12065 -0.2794)
			(end -0.12065 -0.2794)
			(stroke
				(width 0.1)
				(type default)
			)
			(layer "B.Fab")
		)
		(fp_line
			(start -0.12065 -0.2794)
			(end -0.12065 -0.3048)
			(stroke
				(width 0.1)
				(type default)
			)
			(layer "B.Fab")
		)
		(fp_line
			(start 0.12065 0.2794)
			(end 0.12065 0.3048)
			(stroke
				(width 0.1)
				(type default)
			)
			(layer "B.Fab")
		)
		(fp_line
			(start -0.120396 0.2794)
			(end 0.12065 0.2794)
			(stroke
				(width 0.1)
				(type default)
			)
			(layer "B.Fab")
		)
		(fp_line
			(start 0.67945 0.3048)
			(end 0.67945 -0.305054)
			(stroke
				(width 0.1)
				(type default)
			)
			(layer "B.Fab")
		)
		(fp_line
			(start 0.12065 0.3048)
			(end 0.67945 0.3048)
			(stroke
				(width 0.1)
				(type default)
			)
			(layer "B.Fab")
		)
		(fp_line
			(start -0.120396 0.3048)
			(end -0.120396 0.2794)
			(stroke
				(width 0.1)
				(type default)
			)
			(layer "B.Fab")
		)
		(fp_line
			(start -0.67945 0.3048)
			(end -0.120396 0.3048)
			(stroke
				(width 0.1)
				(type default)
			)
			(layer "B.Fab")
		)
		(pad "1" smd circle
			(at 0.40005 0 270)
			(size 0 0)
			(layers "B.Cu" "B.Mask" "B.Paste")
			(net "H_CPU0_PMSYNC_CPU1_R")
		)
		(pad "2" smd circle
			(at -0.40005 0 270)
			(size 0 0)
			(layers "B.Cu" "B.Mask" "B.Paste")
			(net "H_CPU0_PMSYNC_CPU1_R1")
		)
	)
	(footprint ""
		(layer "B.Cu")
		(at 180.449982 -105.120186 90)
		(property "Reference" "R166"
			(at 0 0 90)
			(layer "B.SilkS")
			(hide yes)
			(effects
				(font
					(size 1.27 1.27)
				)
				(justify mirror)
			)
		)
		(property "Value" ""
			(at 0 0 90)
			(layer "B.Fab")
			(effects
				(font
					(size 1.27 1.27)
				)
				(justify mirror)
			)
		)
		(duplicate_pad_numbers_are_jumpers no)
		(fp_line
			(start 0.7874 -0.4064)
			(end -0.7874 -0.4064)
			(stroke
				(width 0.1524)
				(type default)
			)
			(layer "B.SilkS")
		)
		(fp_line
			(start -0.7874 -0.4064)
			(end -0.7874 0.4064)
			(stroke
				(width 0.1524)
				(type default)
			)
			(layer "B.SilkS")
		)
		(fp_line
			(start 0.7874 0.4064)
			(end 0.7874 -0.4064)
			(stroke
				(width 0.1524)
				(type default)
			)
			(layer "B.SilkS")
		)
		(fp_line
			(start -0.7874 0.4064)
			(end 0.7874 0.4064)
			(stroke
				(width 0.1524)
				(type default)
			)
			(layer "B.SilkS")
		)
		(fp_line
			(start 0.67945 -0.305054)
			(end 0.12065 -0.305054)
			(stroke
				(width 0.1)
				(type default)
			)
			(layer "B.Fab")
		)
		(fp_line
			(start 0.12065 -0.305054)
			(end 0.12065 -0.2794)
			(stroke
				(width 0.1)
				(type default)
			)
			(layer "B.Fab")
		)
		(fp_line
			(start -0.12065 -0.3048)
			(end -0.67945 -0.3048)
			(stroke
				(width 0.1)
				(type default)
			)
			(layer "B.Fab")
		)
		(fp_line
			(start -0.67945 -0.3048)
			(end -0.67945 0.3048)
			(stroke
				(width 0.1)
				(type default)
			)
			(layer "B.Fab")
		)
		(fp_line
			(start 0.12065 -0.2794)
			(end -0.12065 -0.2794)
			(stroke
				(width 0.1)
				(type default)
			)
			(layer "B.Fab")
		)
		(fp_line
			(start -0.12065 -0.2794)
			(end -0.12065 -0.3048)
			(stroke
				(width 0.1)
				(type default)
			)
			(layer "B.Fab")
		)
		(fp_line
			(start 0.12065 0.2794)
			(end 0.12065 0.3048)
			(stroke
				(width 0.1)
				(type default)
			)
			(layer "B.Fab")
		)
		(fp_line
			(start -0.120396 0.2794)
			(end 0.12065 0.2794)
			(stroke
				(width 0.1)
				(type default)
			)
			(layer "B.Fab")
		)
		(fp_line
			(start 0.67945 0.3048)
			(end 0.67945 -0.305054)
			(stroke
				(width 0.1)
				(type default)
			)
			(layer "B.Fab")
		)
		(fp_line
			(start 0.12065 0.3048)
			(end 0.67945 0.3048)
			(stroke
				(width 0.1)
				(type default)
			)
			(layer "B.Fab")
		)
		(fp_line
			(start -0.120396 0.3048)
			(end -0.120396 0.2794)
			(stroke
				(width 0.1)
				(type default)
			)
			(layer "B.Fab")
		)
		(fp_line
			(start -0.67945 0.3048)
			(end -0.120396 0.3048)
			(stroke
				(width 0.1)
				(type default)
			)
			(layer "B.Fab")
		)
		(pad "1" smd circle
			(at 0.40005 0 270)
			(size 0 0)
			(layers "B.Cu" "B.Mask" "B.Paste")
			(net "PWRGD_DRAMPWRGD_CPU0_GH_R_LVC1")
		)
		(pad "2" smd circle
			(at -0.40005 0 270)
			(size 0 0)
			(layers "B.Cu" "B.Mask" "B.Paste")
			(net "PWRGD_DRAMPWRGD_CPU0_GH_LVC1_R2")
		)
	)
)
